# S9S_MB_2U (Grand Teton) — schematic netlist excerpt (pin names and nets, part order shuffled) for the footprints in the layout excerpt that follows; sources: Cadence DE-HDL packaged netlist, KiCad conversion of 03242023_DA0F0TMBIJ0_F0T_Motherboard_J_brd_V01_OCP.brd

PR4249  Q_RES  0 5% EMPTY  pkg 0402LF  page 294 : A = PVCCFA_EHV_CPU1_FAULT ; B = GND

Q67  MOSFET_NCH_DUAL  PJT138K IC  pkg SOT363XD  page 148
  S1  = GND
  G1  = BIC_MONITER
  D2  = BIC_MONITER_ISO
  S2  = GND
  G2  = BIC_MONITER_N
  D1  = BIC_MONITER_N

(kicad_pcb
	(version 20260206)
	(generator "pcbnew")
	(generator_version "10.0")
	(general
		(thickness 1.6)
		(legacy_teardrops no)
	)
	(paper "A4")
	(title_block
		(title "03242023_DA0F0TMBIJ0_F0T_Motherboard_J_brd_V01_OCP.brd")
		(comment 1 "Grand Teton / footprints 1695-1696 of 6105")
	)
	(layers
		(0 "F.Cu" signal "TOP")
		(4 "In1.Cu" signal "GND")
		(6 "In2.Cu" signal "IN1")
		(8 "In3.Cu" signal "GND1")
		(10 "In4.Cu" signal "IN2")
		(12 "In5.Cu" signal "GND2")
		(14 "In6.Cu" signal "IN3")
		(16 "In7.Cu" signal "GND3")
		(18 "In8.Cu" signal "VCC")
		(20 "In9.Cu" signal "VCC1")
		(22 "In10.Cu" signal "GND4")
		(24 "In11.Cu" signal "IN4")
		(26 "In12.Cu" signal "GND5")
		(28 "In13.Cu" signal "IN5")
		(30 "In14.Cu" signal "GND6")
		(32 "In15.Cu" signal "IN6")
		(34 "In16.Cu" signal "GND7")
		(2 "B.Cu" signal "BOTTOM")
		(9 "F.Adhes" user "F.Adhesive")
		(11 "B.Adhes" user "B.Adhesive")
		(13 "F.Paste" user "Package Geometry/Pastemask Top")
		(15 "B.Paste" user "Package Geometry/Pastemask Bottom")
		(5 "F.SilkS" user "Ref Des/Silkscreen Top")
		(7 "B.SilkS" user "Ref Des/Silkscreen Bottom")
		(1 "F.Mask" user "Board Geometry/Soldermask Top")
		(3 "B.Mask" user "Board Geometry/Soldermask Bottom")
		(17 "Dwgs.User" user "User.Drawings")
		(19 "Cmts.User" user "User.Comments")
		(21 "Eco1.User" user "User.Eco1")
		(23 "Eco2.User" user "User.Eco2")
		(25 "Edge.Cuts" user "Board Geometry/Outline")
		(27 "Margin" user)
		(31 "F.CrtYd" user "Package Geometry/Place Bound Top")
		(29 "B.CrtYd" user "Package Geometry/Place Bound Bottom")
		(35 "F.Fab" user "Ref Des/Assembly Top")
		(33 "B.Fab" user "Ref Des/Assembly Bottom")
	)
	(footprint ""
		(layer "F.Cu")
		(at 116.13388 -407.16073 -90)
		(property "Reference" "Q67"
			(at 0.973836 1.916176 90)
			(unlocked yes)
			(layer "F.SilkS")
			(effects
				(font
					(size 0.7874 0.5842)
					(thickness 0.1524)
				)
				(justify left)
			)
		)
		(property "Value" ""
			(at 0 0 270)
			(layer "F.Fab")
			(effects
				(font
					(size 1.27 1.27)
				)
			)
		)
		(duplicate_pad_numbers_are_jumpers no)
		(fp_line
			(start -1.332738 1.100074)
			(end -1.332738 -1.100074)
			(stroke
				(width 0.1524)
				(type default)
			)
			(layer "F.SilkS")
		)
		(fp_line
			(start 1.332738 1.100074)
			(end -1.332738 1.100074)
			(stroke
				(width 0.1524)
				(type default)
			)
			(layer "F.SilkS")
		)
		(fp_line
			(start 0 -0.541274)
			(end 0.4826 -1.100074)
			(stroke
				(width 0.1524)
				(type default)
			)
			(layer "F.SilkS")
		)
		(fp_line
			(start -1.332738 -1.100074)
			(end -0.4826 -1.100074)
			(stroke
				(width 0.1524)
				(type default)
			)
			(layer "F.SilkS")
		)
		(fp_line
			(start -0.4826 -1.100074)
			(end 0 -0.541274)
			(stroke
				(width 0.1524)
				(type default)
			)
			(layer "F.SilkS")
		)
		(fp_line
			(start 0.4826 -1.100074)
			(end 1.332738 -1.100074)
			(stroke
				(width 0.1524)
				(type default)
			)
			(layer "F.SilkS")
		)
		(fp_line
			(start 1.332738 -1.100074)
			(end 1.332738 1.100074)
			(stroke
				(width 0.1524)
				(type default)
			)
			(layer "F.SilkS")
		)
		(fp_poly
			(pts
				(xy -1.72974 -1.81737) (xy -1.481582 -1.072896) (xy -2.226056 -1.321054)
			)
			(stroke
				(width 0)
				(type default)
			)
			(fill yes)
			(layer "F.SilkS")
		)
		(fp_line
			(start -0.674878 1.100074)
			(end -0.674878 -1.100074)
			(stroke
				(width 0.1)
				(type default)
			)
			(layer "F.Fab")
		)
		(fp_line
			(start 0.674878 1.100074)
			(end -0.674878 1.100074)
			(stroke
				(width 0.1)
				(type default)
			)
			(layer "F.Fab")
		)
		(fp_line
			(start -0.674878 -1.100074)
			(end 0.674878 -1.100074)
			(stroke
				(width 0.1)
				(type default)
			)
			(layer "F.Fab")
		)
		(fp_line
			(start 0.674878 -1.100074)
			(end 0.674878 1.100074)
			(stroke
				(width 0.1)
				(type default)
			)
			(layer "F.Fab")
		)
		(fp_poly
			(pts
				(xy -2.2352 -0.298958) (xy -2.2352 -1.001014) (xy -1.533144 -0.649986)
			)
			(stroke
				(width 0)
				(type default)
			)
			(fill yes)
			(layer "F.Fab")
		)
		(pad "1" smd rect
			(at -0.94996 -0.649986)
			(size 0.4318 0.508)
			(layers "F.Cu" "F.Mask" "F.Paste")
			(net "GND")
		)
		(pad "2" smd rect
			(at -0.94996 0)
			(size 0.4318 0.508)
			(layers "F.Cu" "F.Mask" "F.Paste")
			(net "BIC_MONITER")
		)
		(pad "3" smd rect
			(at -0.94996 0.649986)
			(size 0.4318 0.508)
			(layers "F.Cu" "F.Mask" "F.Paste")
			(net "BIC_MONITER_ISO")
		)
		(pad "4" smd rect
			(at 0.94996 0.649986)
			(size 0.4318 0.508)
			(layers "F.Cu" "F.Mask" "F.Paste")
			(net "GND")
		)
		(pad "5" smd rect
			(at 0.94996 0)
			(size 0.4318 0.508)
			(layers "F.Cu" "F.Mask" "F.Paste")
			(net "BIC_MONITER_N")
		)
		(pad "6" smd rect
			(at 0.94996 -0.649986)
			(size 0.4318 0.508)
			(layers "F.Cu" "F.Mask" "F.Paste")
			(net "BIC_MONITER_N")
		)
	)
	(footprint ""
		(layer "F.Cu")
		(at 49.57318 -171.473368 180)
		(property "Reference" "PR4249"
			(at 0 0 180)
			(layer "F.SilkS")
			(hide yes)
			(effects
				(font
					(size 1.27 1.27)
				)
			)
		)
		(property "Value" ""
			(at 0 0 180)
			(layer "F.Fab")
			(effects
				(font
					(size 1.27 1.27)
				)
			)
		)
		(duplicate_pad_numbers_are_jumpers no)
		(fp_line
			(start 0.7874 0.4064)
			(end -0.7874 0.4064)
			(stroke
				(width 0.1524)
				(type default)
			)
			(layer "F.SilkS")
		)
		(fp_line
			(start 0.7874 -0.4064)
			(end 0.7874 0.4064)
			(stroke
				(width 0.1524)
				(type default)
			)
			(layer "F.SilkS")
		)
		(fp_line
			(start -0.7874 0.4064)
			(end -0.7874 -0.4064)
			(stroke
				(width 0.1524)
				(type default)
			)
			(layer "F.SilkS")
		)
		(fp_line
			(start -0.7874 -0.4064)
			(end 0.7874 -0.4064)
			(stroke
				(width 0.1524)
				(type default)
			)
			(layer "F.SilkS")
		)
		(fp_line
			(start 0.67945 0.3048)
			(end 0.120396 0.3048)
			(stroke
				(width 0.1)
				(type default)
			)
			(layer "F.Fab")
		)
		(fp_line
			(start 0.67945 -0.3048)
			(end 0.67945 0.3048)
			(stroke
				(width 0.1)
				(type default)
			)
			(layer "F.Fab")
		)
		(fp_line
			(start 0.12065 -0.2794)
			(end 0.12065 -0.3048)
			(stroke
				(width 0.1)
				(type default)
			)
			(layer "F.Fab")
		)
		(fp_line
			(start 0.12065 -0.3048)
			(end 0.67945 -0.3048)
			(stroke
				(width 0.1)
				(type default)
			)
			(layer "F.Fab")
		)
		(fp_line
			(start 0.120396 0.3048)
			(end 0.120396 0.2794)
			(stroke
				(width 0.1)
				(type default)
			)
			(layer "F.Fab")
		)
		(fp_line
			(start 0.120396 0.2794)
			(end -0.12065 0.2794)
			(stroke
				(width 0.1)
				(type default)
			)
			(layer "F.Fab")
		)
		(fp_line
			(start -0.12065 0.3048)
			(end -0.67945 0.3048)
			(stroke
				(width 0.1)
				(type default)
			)
			(layer "F.Fab")
		)
		(fp_line
			(start -0.12065 0.2794)
			(end -0.12065 0.3048)
			(stroke
				(width 0.1)
				(type default)
			)
			(layer "F.Fab")
		)
		(fp_line
			(start -0.12065 -0.2794)
			(end 0.12065 -0.2794)
			(stroke
				(width 0.1)
				(type default)
			)
			(layer "F.Fab")
		)
		(fp_line
			(start -0.12065 -0.305054)
			(end -0.12065 -0.2794)
			(stroke
				(width 0.1)
				(type default)
			)
			(layer "F.Fab")
		)
		(fp_line
			(start -0.67945 0.3048)
			(end -0.67945 -0.305054)
			(stroke
				(width 0.1)
				(type default)
			)
			(layer "F.Fab")
		)
		(fp_line
			(start -0.67945 -0.305054)
			(end -0.12065 -0.305054)
			(stroke
				(width 0.1)
				(type default)
			)
			(layer "F.Fab")
		)
		(pad "1" smd circle
			(at -0.40005 0 180)
			(size 0 0)
			(layers "F.Cu" "F.Mask" "F.Paste")
			(net "PVCCFA_EHV_CPU1_FAULT")
		)
		(pad "2" smd circle
			(at 0.40005 0 180)
			(size 0 0)
			(layers "F.Cu" "F.Mask" "F.Paste")
			(net "GND")
		)
	)
)
